FILE_TYPE = CONNECTIVITY;
{Allegro Design Entry HDL 17.4-2019 S026 (4007227) 1/17/2022}
"PAGE_NUMBER" = 27;
0"NC";
1"PVDD18_S5_P0\g";
2"GND\g";
3"GND\g";
4"GND\g";
5"GND\g";
6"GND\g";
7"GND\g";
8"P1V5_BAT\g";
9"GND\g";
10"GND\g";
11"GND\g";
12"UART_CPU0_SCM_UART1_R_TX";
13"TP_CPU0_UART0_INTR";
14"TP_UART_CPU0_UART0_RTS_N";
15"TP_CPU0_TEST5_CCD8";
16"TP_CPU0_TEST5_CCD7";
17"TP_CPU0_TEST5_CCD5";
18"TP_CPU0_TEST5_CCD1";
19"TP_CPU0_TEST5_CCD0";
20"TP_CPU0_TEST4_CCD11";
21"TP_CPU0_TEST6_X3D3";
22"TP_CPU0_TEST47_IOD0";
23"TP_CPU0_TEST47_CCD3";
24"TP_CPU0_TEST47_IOD1";
25"CPU0_THERMTRIP_R_N";
26"CPU1_THERMTRIP_R_N";
27"CPU0_RTC_LDO_SELECT";
28"VSENSE_PVDDCR_SOC_P0_DP";
29"VSENSE_PVDD18_S5_P0_DP";
30"CPU0_SA1";
31"SVID_PVDDCR_CPU0_P0_SVD_R";
32"SVID_PVDDCR_CPU1_P0_SVD_R";
33"SVID_PVDDCR_CPU1_P0_SVC_R";
34"SVID_PVDDCR_CPU0_P0_SVD";
35"SVID_PVDDCR_CPU0_P0_SVC";
36"SVID_PVDDCR_CPU0_P0_SVTO";
37"SVID_PVDDCR_CPU1_P0_SVC";
38"SVID_PVDDCR_CPU1_P0_SVD";
39"CPU0_PROCHOT_N";
40"TP_VSENSE_PVDD33_S5_P0";
41"VSENSE_PVDDCR_CPU0_P0_DP";
42"VSENSE_PVDDCR_CPU1_P0_DP";
43"VSENSE_PVDD18_S5_P0_DN";
44"VSENSE_VSS_SENSE_C_P0";
45"VSENSE_VSS_SENSE_B_P0";
46"UART_CPU0_UART0_R_TX";
47"UART_CPU0_SCM_UART1_RX";
48"CPU1_XTRIG_L7";
49"CPU0_XTRIG_L7";
50"CPU0_XTRIG_L6";
51"CPU0_XTRIG_L5";
52"PVDD18_S5_P0\g";
53"PVDD18_S5_P0\g";
54"GND\g";
55"GND\g";
56"P3V3_AUX\g";
57"CPU0_XTRIG_R1_L7";
58"TP_CPU0_TEST6_CCD1";
59"TP_CPU0_TEST6_CCD3";
60"CPU0_THERMTRIP_R_N";
61"CPU0_XTRIG_R2_L7";
62"JTAG_CPU0_TCK";
63"JTAG_CPU0_TRST_N";
64"CPU0_XTRIG_R1_L4";
65"CPU0_BP0";
66"TP_CPU0_TEST4_CCD10";
67"TP_CPU0_TEST5_CCD6";
68"CPU0_XTRIG_L6";
69"TP_CPU0_TEST4_CCD8";
70"CPU0_BP3";
71"CPU0_BP2";
72"CPU0_BP1";
73"CPU0_XTRIG_L4";
74"CPU0_XTRIG_R1_L5";
75"CPU0_XTRIG_R1_L6";
76"UART_CPU0_UART0_RX";
77"TP_CPU0_TEST4_IOD";
78"TP_CPU0_TEST5_CCD11";
79"TP_CPU0_TEST6_IOD";
80"TP_CPU0_TEST6_X3D5";
81"TP_CPU0_TEST47_CCD0";
82"CPU0_THERMTRIP_N";
83"APML_CPU0_ALERT_N";
84"APML_CPU0_ALERT_R_N";
85"JTAG_CPU0_TDI";
86"JTAG_CPU0_TRST_N";
87"JTAG_CPU0_TCK";
88"JTAG_CPU0_TMS";
89"JTAG_CPU0_DBREQ_N";
90"JTAG_CPU0_TDO";
91"UART_CPU0_SCM_UART1_TX";
92"FM_BIOS_USB_RECOVERY_R";
93"CPU0_XTRIG_R2_L6";
94"CPU0_XTRIG_L6";
95"CPU0_XTRIG_L7";
96"CPU0_XTRIG_R2_L5";
97"CPU0_XTRIG_L5";
98"CPU0_XTRIG_R2_L4";
99"CPU0_XTRIG_L4";
100"JTAG_CPU0_R_TDO";
101"JTAG_CPU0_TDO";
102"CPU0_SP5R1";
103"CPU0_SP5R2";
104"CPU0_SA0";
105"JTAG_CPU0_DBREQ_N";
106"JTAG_CPU0_TMS";
107"CPU0_THERMTRIP_N";
108"CPU0_XTRIG_L7";
109"CPU0_XTRIG_L6";
110"CPU0_XTRIG_L4";
111"CPU0_XTRIG_L5";
112"CPU0_BP3";
113"CPU0_BP2";
114"CPU0_BP0";
115"CPU0_BP1";
116"TP_CPU0_TEST5_CCD2";
117"TP_CPU0_TEST6_X3D2";
118"TP_CPU0_TEST6_X3D1";
119"TP_CPU0_TEST6_X3D0";
120"TP_CPU0_TEST4_CCD9";
121"TP_CPU0_TEST4_CCD7";
122"TP_CPU0_TEST4_CCD6";
123"TP_CPU0_TEST4_CCD5";
124"TP_CPU0_TEST4_CCD4";
125"TP_CPU0_TEST4_CCD3";
126"TP_CPU0_TEST5_CCD4";
127"TP_CPU0_TEST4_CCD2";
128"TP_CPU0_TEST5_CCD3";
129"TP_CPU0_TEST4_CCD1";
130"TP_CPU0_TEST4_CCD0";
131"TP_CPU0_TEST6_X3D4";
132"TP_CPU0_TEST5_CCD10";
133"TP_CPU0_TEST5_CCD9";
134"CPU0_SA1";
135"CPU0_SP5R4";
136"CPU0_SP5R3";
137"CPU0_CORETYPE1";
138"CPU0_CORETYPE0";
139"CPU0_CORETYPE2";
140"TP_CPU0_TEST47_CCD2";
141"CPU0_SP5R4";
142"CPU0_SP5R3";
143"CPU0_SP5R1";
144"CPU0_SP5R2";
145"CPU0_CORETYPE2";
146"CPU0_CORETYPE1";
147"CPU0_CORETYPE0";
148"NC_CPU0_AZ_BITCLK";
149"NC_CPU0_AZ_RST_N";
150"NC_CPU0_AZ_SDIN0";
151"NC_CPU0_AZ_SDIN1";
152"NC_CPU0_AZ_SDIN2";
153"NC_CPU0_AZ_SDOUT";
154"NC_CPU0_AZ_SYNC";
155"TP_CPU0_TEST47_CCD1";
156"CPU0_PROCHOT_N";
157"CPU0_BP0";
158"TP_CPU0_TEST6_CCD2";
159"TP_CPU0_TEST6_CCD0";
160"CPU0_BP2";
161"CPU0_BP1";
162"FM_P0_PCC0_N";
163"FM_P0_PCC1_N";
164"CPU0_SA0";
165"SVID_PVDDCR_CPU1_P0_SVTO";
166"APML_CPU0_ALERT_N";
167"TP_CPU0_TEST41_IDO";
168"VSENSE_PVDD11_S3_P0_DP";
169"SMB_APML_CPU0_SCL";
170"SMB_APML_CPU0_SDA";
171"JTAG_CPU0_TDI";
172"CPU0_BP3";
173"TP_CPU0_TEST5_IOD";
174"TP_CPU0_TEST50_IOD";
175"PRSNT_CPU0_N";
176"VSENSE_PVDDIO_P0_DP";
177"VSENSE_VSS_SENSE_A_P0";
178"FM_BIOS_USB_RECOVERY";
179"CPU0_XTRIG_L7";
180"CPU1_XTRIG_L6";
181"CPU1_XTRIG_L5";
182"CPU0_XTRIG_L5";
183"CPU1_XTRIG_L4";
184"CPU0_XTRIG_L4";
185"UART_CPU0_UART0_TX";
186"SVID_PVDDCR_CPU0_P0_SVC_R";
%"UNIVERSAL_POWER"
"1","(-8675,4825)","0","pure_quanta_power","I100";
;
HDL_POWER"PVDD18_S5_P0"
CDS_LIB"pure_quanta_power";
"A"1;
%"Q_RES"
"1","(-5725,4575)","2","pure_quanta","I170";
;
LOCATION"R404"
$SEC"1"
CDS_SEC"1"
VALUE"0"
CDS_LIB"pure_quanta"
WATTAGE"1/16W"
MATERIAL"CHIP"
TOLERANCE"5%"
PACK_TYPE"0402LF"
PART_NUMBER"CS00002JB13";
"B"
$PN"2"101;
"A"
$PN"1"100;
%"GENOA_SP5"
"20","(-4275,3500)","0","pure_quanta","I227";
;
LOCATION"U25"
$SEC"20"
CDS_SEC"20"
VALUE"SOCKET6096_13568-001"
MATERIAL"IO"
PART_TYPE"SMLF"
NEEDS_NO_SIZE"TRUE"
CDS_LMAN_SYM_OUTLINE"-600,2425,600,-2425"
CDS_LIB"pure_quanta"
PART_NUMBER"DGA^6000030";
"CORETYPE2"
$PN"D68"139;
"BP3"
$PN"A62"172;
"BP2"
$PN"A63"160;
"BP1"
$PN"C62"161;
"BP0"
$PN"C63"157;
"TEST41_IOD"
$PN"W31"167;
"TEST47_CCD3"
$PN"E32"23;
"TEST6_CCD0"
$PN"AA46"159;
"TEST6_X3D3"
$PN"CJ52"21;
"TEST6_X3D2"
$PN"AA29"117;
"TEST47_IOD1"
$PN"D7"24;
"TEST6_X3D1"
$PN"CJ29"118;
"TEST47_IOD0"
$PN"B58"22;
"TEST6_X3D0"
$PN"AA47"119;
"TEST5_CCD11"
$PN"Y29"78;
"TEST4_CCD11"
$PN"AA28"20;
"TEST5_CCD10"
$PN"CK47"132;
"TEST4_CCD9"
$PN"CK30"120;
"TEST4_CCD10"
$PN"CJ47"66;
"TEST47_CCD2"
$PN"CK46"140;
"TEST4_CCD8"
$PN"AA48"69;
"TEST5_CCD9"
$PN"CK29"133;
"TEST47_CCD1"
$PN"CJ24"155;
"TEST4_CCD7"
$PN"AA27"121;
"TEST50_IOD"
$PN"B61"174;
"TEST5_CCD8"
$PN"Y47"15;
"TEST47_CCD0"
$PN"B60"81;
"TEST4_CCD6"
$PN"CJ50"122;
"TEST5_CCD7"
$PN"AA26"16;
"TEST4_CCD5"
$PN"CJ26"123;
"TEST5_CCD6"
$PN"CJ51"67;
"TEST4_CCD4"
$PN"AA52"124;
"TEST5_CCD5"
$PN"CJ25"17;
"TEST6_IOD"
$PN"AA49"79;
"TEST4_CCD3"
$PN"AA30"125;
"TEST5_CCD4"
$PN"AA53"126;
"TEST5_IOD"
$PN"AA24"173;
"TEST4_CCD2"
$PN"CJ48"127;
"TEST4_IOD"
$PN"AA25"77;
"TEST5_CCD3"
$PN"Y30"128;
"TEST4_CCD1"
$PN"CJ28"129;
"TEST5_CCD2"
$PN"CJ49"116;
"TEST6_CCD3"
$PN"Y46"59;
"TEST4_CCD0"
$PN"AA50"130;
"TEST5_CCD1"
$PN"CJ27"18;
"TEST6_CCD2"
$PN"CJ46"158;
"TEST6_X3D5"
$PN"CJ53"80;
"TEST5_CCD0"
$PN"AA51"19;
"TEST6_CCD1"
$PN"CJ30"58;
"TEST6_X3D4"
$PN"AA23"131;
"VDDCR_CPU0_SENSE"
$PN"C2"41;
"VDDCR_CPU1_SENSE"
$PN"DG3"42;
"VDDCR_SOC_SENSE"
$PN"B3"28;
"VDD_33_S5_SENSE"
$PN"BP53"40;
"VDD_18_S5_SENSE"
$PN"C74"29;
"VDD_11_S3_SENSE"
$PN"DH3"168;
"VDDIO_SENSE"
$PN"BR53"176;
"VSS_SENSE_D"
$PN"B73"43;
"VSS_SENSE_C"
$PN"DJ3"44;
"VSS_SENSE_B"
$PN"BR54"45;
"VSS_SENSE_A"
$PN"C3"177;
"UART1_TXD||AGPIO142"
$PN"DJ32"12;
"UART1_RXD||AGPIO141"
$PN"DH33"47;
"RTC_LDO_SELECT"
$PN"DH8"27;
"TCK"
$PN"B17"62;
"SP5R1"
$PN"C19"102;
"AZ_SDIN1||SW_MCLK"
$PN"D33"151;
"AZ_SDIN0||SW_MDATA3"
$PN"C33"150;
"AZ_RST_L||SW_MDATA1"
$PN"A34"149;
"AZ_SDOUT||SW_MDATA2"
$PN"A32"153;
"AZ_SDIN2||SW_MDATA0"
$PN"A33"152;
"UART0_CTS_L||UART2_TXD||AGPIO135"
$PN"DJ33"92;
"UART0_TXD||AGPIO138"
$PN"DJ34"46;
"UART0_INTR||AGPIO139"
$PN"DG34"13;
"UART0_RTS_L||UART2_RXD||AGPIO137"
$PN"DF34"14;
"UART0_RXD||AGPIO136"
$PN"DG35"76;
"SVC1"
$PN"DJ72"37;
"SVT1"
$PN"DG73"165;
"SVC0"
$PN"A23"35;
"SVD1"
$PN"DH72"38;
"SVT0"
$PN"B21"36;
"SVD0"
$PN"A22"34;
"AZ_SYNC"
$PN"D32"154;
"AZ_BITCLK"
$PN"C32"148;
"PCC1_L \B"
$PN"DG72"163;
"PCC0_L \B"
$PN"C22"162;
"SP5R4"
$PN"DH10"135;
"SP5R3"
$PN"DH73"136;
"SP5R2"
$PN"C68"103;
"CORETYPE1"
$PN"B69"137;
"CORETYPE0"
$PN"C70"138;
"SA1"
$PN"DJ56"134;
"XTRIG_L7 \B"
$PN"A65"61;
"XTRIG_L6 \B"
$PN"A66"93;
"XTRIG_L5 \B"
$PN"C65"96;
"XTRIG_L4 \B"
$PN"C66"98;
"TRST_L \B"
$PN"A17"63;
"TMS"
$PN"A16"106;
"THERMTRIP_L \B"
$PN"DJ9"82;
"TDO"
$PN"C18"100;
"TDI"
$PN"C17"171;
"SID"
$PN"DH71"170;
"SIC"
$PN"DJ71"169;
"SA0"
$PN"DJ55"104;
"PROCHOT_L \B"
$PN"A69"39;
"DBREQ_L \B"
$PN"C16"105;
"CPU_PRESENT_L"
$PN"B66"175;
"ALERT_L \B"
$PN"A68"83;
%"UNIVERSAL_POWER"
"1","(-225,5925)","0","pure_quanta_power","I231";
;
HDL_POWER"PVDD18_S5_P0"
CDS_LIB"pure_quanta_power";
"A"52;
%"Q_RES"
"1","(-2375,1475)","2","pure_quanta","I279";
;
LOCATION"R405"
$SEC"1"
CDS_SEC"1"
VALUE"0"
CDS_LIB"pure_quanta"
WATTAGE"1/16W"
MATERIAL"CHIP"
TOLERANCE"5%"
PACK_TYPE"0402LF"
PART_NUMBER"CS00002JB13";
"B"
$PN"2"46;
"A"
$PN"1"185;
%"Q_RES"
"1","(-2375,1375)","0","pure_quanta","I288";
;
LOCATION"R2318"
$SEC"1"
CDS_SEC"1"
VALUE"0"
CDS_LIB"pure_quanta"
WATTAGE"1/16W"
MATERIAL"CHIP"
TOLERANCE"5%"
PACK_TYPE"0402LF"
PART_NUMBER"CS00002JB13";
"B"
$PN"2"91;
"A"
$PN"1"12;
%"UNIVERSAL_POWER"
"1","(-8000,1575)","0","pure_quanta_power","I293";
;
HDL_POWER"PVDD18_S5_P0"
CDS_LIB"pure_quanta_power";
"A"53;
%"Q_RES"
"2","(-6375,1300)","0","pure_quanta","I294";
;
LOCATION"R403"
$SEC"1"
CDS_SEC"1"
TOLERANCE"1%"
VALUE"1K"
WATTAGE"1/16W"
MATERIAL"CHIP"
PACK_TYPE"0402LF"
CDS_LIB"pure_quanta"
PART_NUMBER"CS21002FB06";
"A"
$PN"1"53;
"B"
$PN"2"89;
%"Q_CAP"
"1","(-6375,600)","0","pure_quanta","I295";
;
LOCATION"C212"
$SEC"1"
CDS_SEC"1"
VOLTAGE"50V"
VALUE"0.001UF"
PACK_TYPE"C0402"
TOLERANCE"10%"
MATERIAL"EMPTY"
CDS_LIB"pure_quanta"
PART_NUMBER"CH30106KB19";
"B"
$PN"2"2;
"A"
$PN"1"89;
%"Q_RES"
"2","(-6675,1300)","0","pure_quanta","I296";
;
LOCATION"R402"
$SEC"1"
CDS_SEC"1"
TOLERANCE"1%"
WATTAGE"1/16W"
VALUE"1K"
MATERIAL"CHIP"
PACK_TYPE"0402LF"
CDS_LIB"pure_quanta"
PART_NUMBER"CS21002FB06";
"A"
$PN"1"53;
"B"
$PN"2"88;
%"Q_CAP"
"1","(-6675,600)","0","pure_quanta","I297";
;
LOCATION"C211"
$SEC"1"
CDS_SEC"1"
VOLTAGE"50V"
PACK_TYPE"C0402"
VALUE"0.001UF"
TOLERANCE"10%"
MATERIAL"EMPTY"
CDS_LIB"pure_quanta"
PART_NUMBER"CH30106KB19";
"B"
$PN"2"3;
"A"
$PN"1"88;
%"GND"
"1","(-6375,300)","0","pure_quanta_power","I298";
;
CDS_LIB"pure_quanta_power"
SIZE"1B"
HDL_POWER"GND";
"A<SIZE-1..0>\NAC"2;
%"GND"
"1","(-6675,300)","0","pure_quanta_power","I299";
;
CDS_LIB"pure_quanta_power"
SIZE"1B"
HDL_POWER"GND";
"A<SIZE-1..0>\NAC"3;
%"Q_RES"
"2","(-7025,1300)","0","pure_quanta","I300";
;
LOCATION"R401"
$SEC"1"
CDS_SEC"1"
TOLERANCE"1%"
VALUE"1K"
MATERIAL"CHIP"
PACK_TYPE"0402LF"
WATTAGE"1/16W"
CDS_LIB"pure_quanta"
PART_NUMBER"CS21002FB06";
"A"
$PN"1"53;
"B"
$PN"2"87;
%"Q_RES"
"2","(-7350,1300)","0","pure_quanta","I301";
;
LOCATION"R400"
$SEC"1"
CDS_SEC"1"
TOLERANCE"1%"
WATTAGE"1/16W"
MATERIAL"CHIP"
VALUE"1K"
PACK_TYPE"0402LF"
CDS_LIB"pure_quanta"
PART_NUMBER"CS21002FB06";
"A"
$PN"1"53;
"B"
$PN"2"86;
%"Q_CAP"
"1","(-7025,600)","0","pure_quanta","I302";
;
LOCATION"C210"
$SEC"1"
CDS_SEC"1"
PACK_TYPE"C0402"
VOLTAGE"50V"
VALUE"0.001UF"
TOLERANCE"10%"
MATERIAL"EMPTY"
CDS_LIB"pure_quanta"
PART_NUMBER"CH30106KB19";
"B"
$PN"2"5;
"A"
$PN"1"87;
%"Q_CAP"
"1","(-7350,600)","0","pure_quanta","I303";
;
LOCATION"C209"
$SEC"1"
CDS_SEC"1"
PACK_TYPE"C0402"
VOLTAGE"50V"
VALUE"0.001UF"
TOLERANCE"10%"
MATERIAL"EMPTY"
CDS_LIB"pure_quanta"
PART_NUMBER"CH30106KB19";
"B"
$PN"2"4;
"A"
$PN"1"86;
%"Q_RES"
"2","(-7675,1300)","0","pure_quanta","I304";
;
LOCATION"R399"
$SEC"1"
CDS_SEC"1"
TOLERANCE"1%"
WATTAGE"1/16W"
MATERIAL"CHIP"
VALUE"1K"
PACK_TYPE"0402LF"
CDS_LIB"pure_quanta"
PART_NUMBER"CS21002FB06";
"A"
$PN"1"53;
"B"
$PN"2"85;
%"Q_RES"
"2","(-8000,1300)","0","pure_quanta","I305";
;
LOCATION"R398"
$SEC"1"
CDS_SEC"1"
TOLERANCE"1%"
WATTAGE"1/16W"
MATERIAL"CHIP"
VALUE"1K"
PACK_TYPE"0402LF"
CDS_LIB"pure_quanta"
PART_NUMBER"CS21002FB06";
"A"
$PN"1"53;
"B"
$PN"2"90;
%"Q_CAP"
"1","(-7675,600)","0","pure_quanta","I306";
;
LOCATION"C208"
$SEC"1"
CDS_SEC"1"
PACK_TYPE"C0402"
VOLTAGE"50V"
VALUE"0.001UF"
TOLERANCE"10%"
MATERIAL"EMPTY"
CDS_LIB"pure_quanta"
PART_NUMBER"CH30106KB19";
"B"
$PN"2"7;
"A"
$PN"1"85;
%"Q_CAP"
"1","(-8000,600)","0","pure_quanta","I307";
;
LOCATION"C207"
$SEC"1"
CDS_SEC"1"
PACK_TYPE"C0402"
VOLTAGE"50V"
VALUE"0.001UF"
TOLERANCE"10%"
MATERIAL"EMPTY"
CDS_LIB"pure_quanta"
PART_NUMBER"CH30106KB19";
"B"
$PN"2"6;
"A"
$PN"1"90;
%"GND"
"1","(-7350,300)","0","pure_quanta_power","I308";
;
CDS_LIB"pure_quanta_power"
SIZE"1B"
HDL_POWER"GND";
"A<SIZE-1..0>\NAC"4;
%"GND"
"1","(-7025,300)","0","pure_quanta_power","I309";
;
CDS_LIB"pure_quanta_power"
SIZE"1B"
HDL_POWER"GND";
"A<SIZE-1..0>\NAC"5;
%"GND"
"1","(-8000,300)","0","pure_quanta_power","I310";
;
CDS_LIB"pure_quanta_power"
SIZE"1B"
HDL_POWER"GND";
"A<SIZE-1..0>\NAC"6;
%"GND"
"1","(-7675,300)","0","pure_quanta_power","I311";
;
SIZE"1B"
CDS_LIB"pure_quanta_power"
HDL_POWER"GND";
"A<SIZE-1..0>\NAC"7;
%"Q_RES"
"1","(-6350,5325)","0","pure_quanta","I318";
;
LOCATION"PR59"
$SEC"1"
CDS_SEC"1"
VALUE"0"
CDS_LIB"pure_quanta"
WATTAGE"1/16W"
MATERIAL"CHIP"
TOLERANCE"5%"
PACK_TYPE"0402LF"
PART_NUMBER"CS00002JB13";
"B"
$PN"2"37;
"A"
$PN"1"33;
%"Q_RES"
"1","(-6350,5275)","0","pure_quanta","I319";
;
LOCATION"PR60"
$SEC"1"
CDS_SEC"1"
VALUE"0"
CDS_LIB"pure_quanta"
WATTAGE"1/16W"
MATERIAL"CHIP"
TOLERANCE"5%"
PACK_TYPE"0402LF"
PART_NUMBER"CS00002JB13";
"B"
$PN"2"38;
"A"
$PN"1"32;
%"Q_RES"
"1","(-6350,5475)","0","pure_quanta","I322";
;
LOCATION"PR303"
$SEC"1"
CDS_SEC"1"
VALUE"0"
CDS_LIB"pure_quanta"
WATTAGE"1/16W"
MATERIAL"CHIP"
TOLERANCE"5%"
PACK_TYPE"0402LF"
PART_NUMBER"CS00002JB13";
"B"
$PN"2"34;
"A"
$PN"1"31;
%"Q_RES"
"1","(-6350,5525)","0","pure_quanta","I323";
;
LOCATION"PR302"
$SEC"1"
CDS_SEC"1"
VALUE"0"
CDS_LIB"pure_quanta"
WATTAGE"1/16W"
MATERIAL"CHIP"
TOLERANCE"5%"
PACK_TYPE"0402LF"
PART_NUMBER"CS00002JB13";
"B"
$PN"2"35;
"A"
$PN"1"186;
%"Q_RES"
"1","(-1475,2900)","0","pure_quanta","I334";
;
LOCATION"R483"
$SEC"1"
CDS_SEC"1"
VALUE"0"
CDS_LIB"pure_quanta"
WATTAGE"1/16W"
MATERIAL"CHIP"
TOLERANCE"5%"
PACK_TYPE"0402LF"
PART_NUMBER"CS00002JB13";
"B"
$PN"2"74;
"A"
$PN"1"51;
%"Q_RES"
"1","(-1475,2950)","0","pure_quanta","I335";
;
LOCATION"R481"
$SEC"1"
CDS_SEC"1"
VALUE"0"
CDS_LIB"pure_quanta"
WATTAGE"1/16W"
MATERIAL"CHIP"
TOLERANCE"5%"
PACK_TYPE"0402LF"
PART_NUMBER"CS00002JB13";
"B"
$PN"2"64;
"A"
$PN"1"73;
%"Q_RES"
"1","(-1475,2850)","0","pure_quanta","I336";
;
LOCATION"R484"
$SEC"1"
CDS_SEC"1"
VALUE"0"
CDS_LIB"pure_quanta"
WATTAGE"1/16W"
MATERIAL"CHIP"
TOLERANCE"5%"
PACK_TYPE"0402LF"
PART_NUMBER"CS00002JB13";
"B"
$PN"2"75;
"A"
$PN"1"50;
%"Q_RES"
"1","(-1475,2800)","0","pure_quanta","I337";
;
LOCATION"R485"
$SEC"1"
CDS_SEC"1"
VALUE"0"
CDS_LIB"pure_quanta"
WATTAGE"1/16W"
MATERIAL"CHIP"
TOLERANCE"5%"
PACK_TYPE"0402LF"
PART_NUMBER"CS00002JB13";
"B"
$PN"2"57;
"A"
$PN"1"49;
%"Q_RES"
"1","(-2725,4575)","0","pure_quanta","I346";
;
LOCATION"R156"
$SEC"1"
CDS_SEC"1"
VALUE"0"
CDS_LIB"pure_quanta"
WATTAGE"1/16W"
MATERIAL"CHIP"
TOLERANCE"5%"
PACK_TYPE"0402LF"
PART_NUMBER"CS00002JB13";
"B"
$PN"2"99;
"A"
$PN"1"98;
%"Q_RES"
"1","(-2725,4525)","0","pure_quanta","I347";
;
LOCATION"R157"
$SEC"1"
CDS_SEC"1"
VALUE"0"
CDS_LIB"pure_quanta"
WATTAGE"1/16W"
MATERIAL"CHIP"
TOLERANCE"5%"
PACK_TYPE"0402LF"
PART_NUMBER"CS00002JB13";
"B"
$PN"2"97;
"A"
$PN"1"96;
%"Q_RES"
"1","(-2725,4425)","0","pure_quanta","I348";
;
LOCATION"R357"
$SEC"1"
CDS_SEC"1"
VALUE"0"
CDS_LIB"pure_quanta"
PACK_TYPE"0402LF"
TOLERANCE"5%"
MATERIAL"CHIP"
WATTAGE"1/16W"
PART_NUMBER"CS00002JB13";
"B"
$PN"2"95;
"A"
$PN"1"61;
%"Q_RES"
"1","(-2725,4475)","0","pure_quanta","I349";
;
LOCATION"R356"
$SEC"1"
CDS_SEC"1"
VALUE"0"
CDS_LIB"pure_quanta"
WATTAGE"1/16W"
MATERIAL"CHIP"
TOLERANCE"5%"
PACK_TYPE"0402LF"
PART_NUMBER"CS00002JB13";
"B"
$PN"2"94;
"A"
$PN"1"93;
%"Q_RES"
"1","(-2500,1625)","0","pure_quanta","I353";
;
LOCATION"R1204"
$SEC"1"
CDS_SEC"1"
VALUE"0"
CDS_LIB"pure_quanta"
WATTAGE"1/16W"
MATERIAL"CHIP"
TOLERANCE"5%"
PACK_TYPE"0402LF"
PART_NUMBER"CS00002JB13";
"B"
$PN"2"178;
"A"
$PN"1"92;
%"TP"
"1","(-5975,1625)","6","pure_quanta","I355";
;
LOCATION"TP9"
$SEC"1"
CDS_SEC"1"
MATERIAL"NA"
PACK_TYPE"TP"
CDS_LIB"pure_quanta"
PART_NUMBER"TP30";
"TP \B"
$PN"1"
$PIN_NUMBER"?"29;
%"TP"
"1","(-6125,1625)","6","pure_quanta","I356";
;
LOCATION"TP8"
$SEC"1"
CDS_SEC"1"
MATERIAL"NA"
PACK_TYPE"TP"
CDS_LIB"pure_quanta"
PART_NUMBER"TP30";
"TP \B"
$PN"1"
$PIN_NUMBER"?"168;
%"TP"
"1","(-6200,1625)","6","pure_quanta","I357";
;
LOCATION"TP7"
$SEC"1"
CDS_SEC"1"
MATERIAL"NA"
PACK_TYPE"TP"
CDS_LIB"pure_quanta"
PART_NUMBER"TP30";
"TP \B"
$PN"1"
$PIN_NUMBER"?"41;
%"TP"
"1","(-6275,1625)","6","pure_quanta","I358";
;
LOCATION"TP6"
$SEC"1"
CDS_SEC"1"
MATERIAL"NA"
PACK_TYPE"TP"
CDS_LIB"pure_quanta"
PART_NUMBER"TP30";
"TP \B"
$PN"1"
$PIN_NUMBER"?"42;
%"TP"
"1","(-6350,1625)","6","pure_quanta","I359";
;
LOCATION"TP5"
$SEC"1"
CDS_SEC"1"
MATERIAL"NA"
PACK_TYPE"TP"
CDS_LIB"pure_quanta"
PART_NUMBER"TP30";
"TP \B"
$PN"1"
$PIN_NUMBER"?"176;
%"TP"
"1","(-6475,1625)","6","pure_quanta","I360";
;
LOCATION"TP4"
$SEC"1"
CDS_SEC"1"
MATERIAL"NA"
PACK_TYPE"TP"
CDS_LIB"pure_quanta"
PART_NUMBER"TP30";
"TP \B"
$PN"1"
$PIN_NUMBER"?"43;
%"TP"
"1","(-6550,1625)","6","pure_quanta","I361";
;
LOCATION"TP3"
$SEC"1"
CDS_SEC"1"
MATERIAL"NA"
PACK_TYPE"TP"
CDS_LIB"pure_quanta"
PART_NUMBER"TP30";
"TP \B"
$PN"1"
$PIN_NUMBER"?"44;
%"TP"
"1","(-6625,1625)","6","pure_quanta","I362";
;
LOCATION"TP2"
$SEC"1"
CDS_SEC"1"
MATERIAL"NA"
PACK_TYPE"TP"
CDS_LIB"pure_quanta"
PART_NUMBER"TP30";
"TP \B"
$PN"1"
$PIN_NUMBER"?"45;
%"UNIVERSAL_GND"
"1","(-150,2650)","0","pure_quanta_power","I364";
;
CDS_LIB"pure_quanta_power"
HDL_POWER"GND";
"A"54;
%"UNIVERSAL_GND"
"1","(-150,2025)","0","pure_quanta_power","I365";
;
CDS_LIB"pure_quanta_power"
HDL_POWER"GND";
"A"55;
%"UNIVERSAL_POWER"
"1","(-9050,3400)","0","pure_quanta_power","I366";
;
HDL_POWER"P3V3_AUX"
CDS_LIB"pure_quanta_power";
"A"56;
%"Q_RES"
"1","(-575,5400)","0","pure_quanta","I377";
;
LOCATION"R412"
$SEC"1"
CDS_SEC"1"
VALUE"2.2K"
PACK_TYPE"0402LF"
TOLERANCE"5%"
MATERIAL"CHIP"
WATTAGE"1/16W"
CDS_LIB"pure_quanta"
PART_NUMBER"CS22202JB07";
"B"
$PN"2"52;
"A"
$PN"1"156;
%"Q_RES"
"1","(-575,5100)","0","pure_quanta","I378";
;
LOCATION"R418"
$SEC"1"
CDS_SEC"1"
VALUE"2.2K"
PACK_TYPE"0402LF"
TOLERANCE"5%"
MATERIAL"CHIP"
WATTAGE"1/16W"
CDS_LIB"pure_quanta"
PART_NUMBER"CS22202JB07";
"B"
$PN"2"52;
"A"
$PN"1"166;
%"Q_RES"
"1","(-575,5150)","0","pure_quanta","I379";
;
LOCATION"R417"
$SEC"1"
CDS_SEC"1"
VALUE"2.2K"
PACK_TYPE"0402LF"
TOLERANCE"5%"
MATERIAL"CHIP"
WATTAGE"1/16W"
CDS_LIB"pure_quanta"
PART_NUMBER"CS22202JB07";
"B"
$PN"2"52;
"A"
$PN"1"107;
%"Q_RES"
"1","(-575,5600)","0","pure_quanta","I380";
;
LOCATION"R408"
$SEC"1"
CDS_SEC"1"
VALUE"2.2K"
PACK_TYPE"0402LF"
TOLERANCE"5%"
MATERIAL"CHIP"
WATTAGE"1/16W"
CDS_LIB"pure_quanta"
PART_NUMBER"CS22202JB07";
"B"
$PN"2"52;
"A"
$PN"1"114;
%"Q_RES"
"1","(-575,5550)","0","pure_quanta","I381";
;
LOCATION"R409"
$SEC"1"
CDS_SEC"1"
VALUE"2.2K"
PACK_TYPE"0402LF"
TOLERANCE"5%"
MATERIAL"CHIP"
WATTAGE"1/16W"
CDS_LIB"pure_quanta"
PART_NUMBER"CS22202JB07";
"B"
$PN"2"52;
"A"
$PN"1"115;
%"Q_RES"
"1","(-575,5500)","0","pure_quanta","I382";
;
LOCATION"R410"
$SEC"1"
CDS_SEC"1"
VALUE"2.2K"
PACK_TYPE"0402LF"
TOLERANCE"5%"
MATERIAL"CHIP"
WATTAGE"1/16W"
CDS_LIB"pure_quanta"
PART_NUMBER"CS22202JB07";
"B"
$PN"2"52;
"A"
$PN"1"113;
%"Q_RES"
"1","(-575,5450)","0","pure_quanta","I383";
;
LOCATION"R411"
$SEC"1"
CDS_SEC"1"
VALUE"2.2K"
PACK_TYPE"0402LF"
TOLERANCE"5%"
MATERIAL"CHIP"
WATTAGE"1/16W"
CDS_LIB"pure_quanta"
PART_NUMBER"CS22202JB07";
"B"
$PN"2"52;
"A"
$PN"1"112;
%"Q_RES"
"1","(-575,5350)","0","pure_quanta","I384";
;
LOCATION"R413"
$SEC"1"
CDS_SEC"1"
VALUE"2.2K"
PACK_TYPE"0402LF"
TOLERANCE"5%"
MATERIAL"CHIP"
WATTAGE"1/16W"
CDS_LIB"pure_quanta"
PART_NUMBER"CS22202JB07";
"B"
$PN"2"52;
"A"
$PN"1"110;
%"Q_RES"
"1","(-575,5300)","0","pure_quanta","I385";
;
LOCATION"R414"
$SEC"1"
CDS_SEC"1"
VALUE"2.2K"
PACK_TYPE"0402LF"
TOLERANCE"5%"
MATERIAL"CHIP"
WATTAGE"1/16W"
CDS_LIB"pure_quanta"
PART_NUMBER"CS22202JB07";
"B"
$PN"2"52;
"A"
$PN"1"111;
%"Q_RES"
"1","(-575,5250)","0","pure_quanta","I386";
;
LOCATION"R415"
$SEC"1"
CDS_SEC"1"
VALUE"2.2K"
PACK_TYPE"0402LF"
TOLERANCE"5%"
MATERIAL"CHIP"
WATTAGE"1/16W"
CDS_LIB"pure_quanta"
PART_NUMBER"CS22202JB07";
"B"
$PN"2"52;
"A"
$PN"1"109;
%"Q_RES"
"1","(-575,5200)","0","pure_quanta","I387";
;
LOCATION"R416"
$SEC"1"
CDS_SEC"1"
VALUE"2.2K"
PACK_TYPE"0402LF"
TOLERANCE"5%"
MATERIAL"CHIP"
WATTAGE"1/16W"
CDS_LIB"pure_quanta"
PART_NUMBER"CS22202JB07";
"B"
$PN"2"52;
"A"
$PN"1"108;
%"Q_RES"
"1","(-8700,2850)","0","pure_quanta","I388";
;
LOCATION"R387"
$SEC"1"
CDS_SEC"1"
VALUE"2.2K"
PACK_TYPE"0402LF"
TOLERANCE"5%"
MATERIAL"CHIP"
WATTAGE"1/16W"
CDS_LIB"pure_quanta"
PART_NUMBER"CS22202JB07";
"B"
$PN"2"145;
"A"
$PN"1"56;
%"Q_RES"
"1","(-8700,2900)","0","pure_quanta","I389";
;
LOCATION"R388"
$SEC"1"
CDS_SEC"1"
VALUE"2.2K"
PACK_TYPE"0402LF"
TOLERANCE"5%"
MATERIAL"CHIP"
WATTAGE"1/16W"
CDS_LIB"pure_quanta"
PART_NUMBER"CS22202JB07";
"B"
$PN"2"146;
"A"
$PN"1"56;
%"Q_RES"
"1","(-8700,2950)","0","pure_quanta","I390";
;
LOCATION"R390"
$SEC"1"
CDS_SEC"1"
VALUE"2.2K"
PACK_TYPE"0402LF"
TOLERANCE"5%"
MATERIAL"CHIP"
WATTAGE"1/16W"
CDS_LIB"pure_quanta"
PART_NUMBER"CS22202JB07";
"B"
$PN"2"147;
"A"
$PN"1"56;
%"Q_RES"
"1","(-8700,3000)","0","pure_quanta","I391";
;
LOCATION"R389"
$SEC"1"
CDS_SEC"1"
VALUE"2.2K"
PACK_TYPE"0402LF"
TOLERANCE"5%"
MATERIAL"CHIP"
WATTAGE"1/16W"
CDS_LIB"pure_quanta"
PART_NUMBER"CS22202JB07";
"B"
$PN"2"141;
"A"
$PN"1"56;
%"Q_RES"
"1","(-8700,3050)","0","pure_quanta","I392";
;
LOCATION"R391"
$SEC"1"
CDS_SEC"1"
VALUE"2.2K"
PACK_TYPE"0402LF"
TOLERANCE"5%"
MATERIAL"CHIP"
WATTAGE"1/16W"
CDS_LIB"pure_quanta"
PART_NUMBER"CS22202JB07";
"B"
$PN"2"142;
"A"
$PN"1"56;
%"Q_RES"
"1","(-8700,3100)","0","pure_quanta","I393";
;
LOCATION"R396"
$SEC"1"
CDS_SEC"1"
VALUE"2.2K"
PACK_TYPE"0402LF"
TOLERANCE"5%"
MATERIAL"CHIP"
WATTAGE"1/16W"
CDS_LIB"pure_quanta"
PART_NUMBER"CS22202JB07";
"B"
$PN"2"144;
"A"
$PN"1"56;
%"Q_RES"
"1","(-8700,3150)","0","pure_quanta","I394";
;
LOCATION"R397"
$SEC"1"
CDS_SEC"1"
VALUE"2.2K"
PACK_TYPE"0402LF"
TOLERANCE"5%"
MATERIAL"CHIP"
WATTAGE"1/16W"
CDS_LIB"pure_quanta"
PART_NUMBER"CS22202JB07";
"B"
$PN"2"143;
"A"
$PN"1"56;
%"Q_RES"
"2","(-8675,4650)","2","pure_quanta","I395";
;
LOCATION"R392"
$SEC"1"
CDS_SEC"1"
PACK_TYPE"0402LF"
VALUE"2.2K"
MATERIAL"EMPTY"
TOLERANCE"5%"
WATTAGE"1/16W"
CDS_LIB"pure_quanta"
PART_NUMBER"CS22202JB07";
"A"
$PN"1"1;
"B"
$PN"2"164;
%"Q_RES"
"2","(-8675,4350)","2","pure_quanta","I396";
;
LOCATION"R393"
$SEC"1"
CDS_SEC"1"
PACK_TYPE"0402LF"
VALUE"2.2K"
MATERIAL"CHIP"
TOLERANCE"5%"
WATTAGE"1/16W"
CDS_LIB"pure_quanta"
PART_NUMBER"CS22202JB07";
"A"
$PN"1"164;
"B"
$PN"2"11;
%"Q_RES"
"2","(-8550,4350)","0","pure_quanta","I397";
;
LOCATION"R394"
$SEC"1"
CDS_SEC"1"
PACK_TYPE"0402LF"
VALUE"2.2K"
MATERIAL"CHIP"
TOLERANCE"5%"
WATTAGE"1/16W"
CDS_LIB"pure_quanta"
PART_NUMBER"CS22202JB07";
"A"
$PN"1"30;
"B"
$PN"2"10;
%"Q_RES"
"1","(-2725,4725)","0","pure_quanta","I399";
;
LOCATION"R489"
$SEC"1"
CDS_SEC"1"
VALUE"33"
PACK_TYPE"0402LF"
TOLERANCE"5%"
MATERIAL"CHIP"
WATTAGE"1/16W"
CDS_LIB"pure_quanta"
BOM_COST"MEM"
PART_NUMBER"CS03302JB10";
"B"
$PN"2"60;
"A"
$PN"1"82;
%"Q_RES"
"1","(-2725,4875)","0","pure_quanta","I401";
;
LOCATION"R247"
$SEC"1"
CDS_SEC"1"
VALUE"33"
PACK_TYPE"0402LF"
TOLERANCE"5%"
MATERIAL"CHIP"
WATTAGE"1/16W"
BOM_COST"MEM"
CDS_LIB"pure_quanta"
PART_NUMBER"CS03302JB10";
"B"
$PN"2"84;
"A"
$PN"1"83;
%"TP"
"1","(-5900,1625)","4","pure_quanta","I403";
;
LOCATION"TP10"
$SEC"1"
CDS_SEC"1"
MATERIAL"NA"
PACK_TYPE"TP"
CDS_LIB"pure_quanta"
PART_NUMBER"TP26";
"TP \B"
$PN"1"
$PIN_NUMBER"?"28;
%"TP"
"1","(-6700,1625)","4","pure_quanta","I404";
;
LOCATION"TP1"
$SEC"1"
CDS_SEC"1"
MATERIAL"NA"
PACK_TYPE"TP"
CDS_LIB"pure_quanta"
PART_NUMBER"TP26";
"TP \B"
$PN"1"
$PIN_NUMBER"?"177;
%"UNIVERSAL_POWER"
"1","(-5650,1575)","0","pure_quanta_power","I408";
;
HDL_POWER"P1V5_BAT"
CDS_LIB"pure_quanta_power";
"A"8;
%"UNIVERSAL_GND"
"1","(-5650,625)","0","pure_quanta_power","I410";
;
CDS_LIB"pure_quanta_power"
HDL_POWER"GND";
"A"9;
%"CONN10_HBC1051L300D8H"
"1","(-1475,750)","0","pure_quanta","I423";
;
LOCATION"J212"
SEC"1"
MATERIAL"IO"
PART_TYPE"THLF"
VALUE"CONN10_HBC1051-L300D-8H"
CDS_LIB"pure_quanta"
NEEDS_NO_SIZE"TRUE"
CDS_LMAN_SYM_OUTLINE"-125,250,125,-250"
SEC_TYPE""
PART_NUMBER"DFHD10MS117";
"10"
$PN"10"0;
"8"
$PN"8"48;
"9"
$PN"9"0;
"7"
$PN"7"179;
"6"
$PN"6"180;
"5"
$PN"5"68;
"4"
$PN"4"181;
"3"
$PN"3"182;
"2"
$PN"2"183;
"1"
$PN"1"184;
%"SCONN8_G802M0083150RD3HR"
"1","(-500,2250)","0","pure_quanta","I424";
;
LOCATION"J48"
SEC"1"
VALUE"SCONN8_G802M0083150RD3HR"
PART_TYPE"SMLF"
MATERIAL"IO"
CDS_LMAN_SYM_OUTLINE"-125,125,125,-125"
NEEDS_NO_SIZE"TRUE"
CDS_LIB"pure_quanta"
SEC_TYPE""
PART_NUMBER"DFHD08MS385";
"8"
$PN"8"55;
"7"
$PN"7"70;
"6"
$PN"6"55;
"5"
$PN"5"71;
"4"
$PN"4"55;
"3"
$PN"3"72;
"2"
$PN"2"55;
"1"
$PN"1"65;
%"SCONN8_G802M0083150RD3HR"
"1","(-500,2875)","0","pure_quanta","I425";
;
LOCATION"J5"
SEC"1"
VALUE"SCONN8_G802M0083150RD3HR"
MATERIAL"IO"
PART_TYPE"SMLF"
CDS_LMAN_SYM_OUTLINE"-125,125,125,-125"
NEEDS_NO_SIZE"TRUE"
CDS_LIB"pure_quanta"
SEC_TYPE""
PART_NUMBER"DFHD08MS385";
"8"
$PN"8"54;
"7"
$PN"7"57;
"6"
$PN"6"54;
"5"
$PN"5"75;
"4"
$PN"4"54;
"3"
$PN"3"74;
"2"
$PN"2"54;
"1"
$PN"1"64;
%"Q_RES"
"2","(-5650,1350)","0","pure_quanta","I427";
;
LOCATION"R5055"
$SEC"1"
CDS_SEC"1"
VALUE"10K"
PACK_TYPE"0402LF"
TOLERANCE"5%"
MATERIAL"CHIP"
WATTAGE"1/16W"
CDS_LIB"pure_quanta"
BOM_COST"I/O CONNECTOR"
PART_NUMBER"CS31002JB08";
"A"
$PN"1"8;
"B"
$PN"2"27;
%"Q_RES"
"2","(-5650,900)","0","pure_quanta","I428";
;
LOCATION"R5056"
$SEC"1"
CDS_SEC"1"
PACK_TYPE"0402LF"
TOLERANCE"5%"
MATERIAL"EMPTY"
VALUE"10K"
WATTAGE"1/16W"
BOM_COST"I/O CONNECTOR"
CDS_LIB"pure_quanta"
PART_NUMBER"CS31002JB08";
"A"
$PN"1"27;
"B"
$PN"2"9;
%"Q_RES"
"1","(-1075,3825)","0","pure_quanta","I429";
;
LOCATION"R1533"
$SEC"1"
CDS_SEC"1"
TOLERANCE"5%"
VALUE"0"
WATTAGE"1/16W"
PACK_TYPE"0402LF"
MATERIAL"CHIP"
CDS_LIB"pure_quanta"
PART_NUMBER"CS00002JB13";
"B"
$PN"2"26;
"A"
$PN"1"25;
%"GND"
"1","(-8550,4150)","0","pure_quanta_power","I95";
;
SIZE"1B"
CDS_LIB"pure_quanta_power"
HDL_POWER"GND";
"A<SIZE-1..0>\NAC"10;
%"GND"
"1","(-8675,4150)","0","pure_quanta_power","I96";
;
SIZE"1B"
CDS_LIB"pure_quanta_power"
HDL_POWER"GND";
"A<SIZE-1..0>\NAC"11;
END.
